FILE_TYPE = CONNECTIVITY;
{Allegro Design Entry HDL 17.2-2016 S081 (4005846) 1/11/2022}
"PAGE_NUMBER" = 91;
0"NC";
1"M_G_CPU0_SA_CB<7:0>";
2"M_G_CPU0_SB_CA<6:0>";
3"M_G_CPU0_SA_CA<6:0>";
4"M_G_CPU0_SB_CB<7:0>";
5"M_G_CPU0_SA_DQ<31:0>";
6"M_G_CPU0_SB_DQ<31:0>";
7"M_G_CPU0_SA_DQS_DP<9:0>";
8"M_G_CPU0_SB_DQS_DN<9:0>";
9"M_G_CPU0_SB_DQS_DP<9:0>";
10"GND\g";
11"GND\g";
12"P3V3_STBY\g";
13"P3V3_STBY\g";
14"M_G_CPU0_SA_DQS_DN<9:0>";
15"P3V3_STBY\g";
16"PD_CHG_CPU0_DIMM0_SAA";
17"I3C_SPD_DDRGL_CPU0_SDA";
18"I3C_SPD_DDRG_CPU0_SCL";
19"I3C_SPD_DDRGL_CPU0_SCL";
20"M_G_CPU0_ALERT_N";
21"PWRGD_CHG_CPU0_DIMM0";
22"M_G_CPU0_RESET_N";
23"M_G_CPU0_SA_CA<0>";
24"M_G_CPU0_SB_CA<6>";
25"M_G_CPU0_SB_CA<5>";
26"M_G_CPU0_SB_CA<4>";
27"M_G_CPU0_SB_CA<3>";
28"GND\g";
29"P12V_MEM_0\g";
30"GND\g";
31"M_G_CPU0_SA_DQ<12>";
32"M_G_CPU0_SA_DQ<13>";
33"M_G_CPU0_SA_DQ<15>";
34"M_G_CPU0_SA_DQ<16>";
35"M_G_CPU0_SA_DQ<17>";
36"M_G_CPU0_SA_DQ<18>";
37"M_G_CPU0_SA_DQ<11>";
38"M_G_CPU0_SA_DQ<10>";
39"M_G_CPU0_SA_DQ<9>";
40"M_G_CPU0_SA_DQ<8>";
41"M_G_CPU0_SA_DQ<7>";
42"M_G_CPU0_SA_DQ<21>";
43"M_G_CPU0_SA_DQ<20>";
44"M_G_CPU0_SA_DQ<19>";
45"M_G_CPU0_SB_DQS_DP<9>";
46"M_G_CPU0_SB_DQS_DN<9>";
47"M_G_CPU0_SA_DQS_DP<9>";
48"M_G_CPU0_SA_DQS_DN<9>";
49"M_G_CPU0_SA_DQS_DP<8>";
50"M_G_CPU0_SA_DQS_DN<8>";
51"M_G_CPU0_SB_DQS_DN<7>";
52"M_G_CPU0_SA_DQS_DP<7>";
53"M_G_CPU0_SB_DQS_DP<6>";
54"M_G_CPU0_SB_DQS_DN<6>";
55"M_G_CPU0_SA_DQS_DN<6>";
56"M_G_CPU0_SB_DQS_DP<5>";
57"M_G_CPU0_SB_DQS_DN<5>";
58"M_G_CPU0_SA_DQS_DP<5>";
59"M_G_CPU0_SA_DQS_DN<5>";
60"M_G_CPU0_SB_DQS_DP<4>";
61"M_G_CPU0_SB_DQS_DN<4>";
62"M_G_CPU0_SA_DQS_DP<4>";
63"M_G_CPU0_SA_DQS_DN<4>";
64"M_G_CPU0_SB_DQS_DP<3>";
65"M_G_CPU0_SB_DQS_DN<3>";
66"M_G_CPU0_SA_DQS_DP<3>";
67"M_G_CPU0_SA_DQS_DN<3>";
68"M_G_CPU0_SB_DQS_DP<2>";
69"M_G_CPU0_SB_DQS_DN<2>";
70"M_G_CPU0_SA_DQS_DP<2>";
71"M_G_CPU0_SA_DQS_DN<2>";
72"M_G_CPU0_SB_DQS_DP<1>";
73"M_G_CPU0_SB_DQS_DN<1>";
74"M_G_CPU0_SA_DQS_DP<1>";
75"M_G_CPU0_SA_DQS_DN<1>";
76"M_G_CPU0_SB_DQS_DP<0>";
77"M_G_CPU0_SB_DQS_DN<0>";
78"M_G_CPU0_SA_DQS_DP<0>";
79"M_G_CPU0_SA_DQS_DN<0>";
80"M_G_CPU0_SB_DQS_DP<7>";
81"M_G_CPU0_SB_DQS_DN<8>";
82"M_G_CPU0_SB_DQS_DP<8>";
83"M_G_CPU0_SA_DQS_DP<6>";
84"M_G_CPU0_SA_DQS_DN<7>";
85"M_G_CPU0_SA_DQ<22>";
86"M_G_CPU0_SA_DQ<23>";
87"M_G_CPU0_SA_DQ<24>";
88"M_G_CPU0_SA_DQ<25>";
89"M_G_CPU0_SA_DQ<30>";
90"M_G_CPU0_SA_DQ<31>";
91"TP_CHG_CPU0_DIMM0_RFU_0";
92"TP_CHG_CPU0_DIMM0_RFU_1";
93"TP_CHG_CPU0_DIMM0_RFU_2";
94"TP_CHG_CPU0_DIMM0_RFU_3";
95"TP_CHG_CPU0_DIMM0_RFU_4";
96"TP_CHG_CPU0_DIMM0_RFU_5";
97"TP_CHG_CPU0_DIMM0_RFU_6";
98"M_G_CPU0_SB_PAR";
99"M_G_CPU0_SA_PAR";
100"M_G_CPU0_SB_RSP<0>";
101"M_G_CPU0_SA_RSP<0>";
102"M_G_CPU0_SB_DQ<0>";
103"M_G_CPU0_SB_DQ<1>";
104"M_G_CPU0_SB_DQ<2>";
105"M_G_CPU0_SB_DQ<3>";
106"M_G_CPU0_SB_DQ<4>";
107"M_G_CPU0_SB_DQ<5>";
108"M_G_CPU0_SB_DQ<6>";
109"M_G_CPU0_SB_DQ<7>";
110"M_G_CPU0_SB_DQ<8>";
111"M_G_CPU0_SB_DQ<9>";
112"M_G_CPU0_SB_DQ<10>";
113"M_G_CPU0_SB_DQ<11>";
114"M_G_CPU0_SB_DQ<12>";
115"M_G_CPU0_SB_DQ<13>";
116"M_G_CPU0_SB_DQ<14>";
117"M_G_CPU0_SB_DQ<15>";
118"M_G_CPU0_SB_DQ<16>";
119"M_G_CPU0_SB_DQ<17>";
120"M_G_CPU0_SB_DQ<18>";
121"M_G_CPU0_SB_DQ<19>";
122"M_G_CPU0_SB_DQ<20>";
123"M_G_CPU0_SB_DQ<21>";
124"M_G_CPU0_SB_DQ<22>";
125"M_G_CPU0_SB_DQ<23>";
126"M_G_CPU0_SB_DQ<24>";
127"M_G_CPU0_SB_DQ<25>";
128"M_G_CPU0_SB_DQ<26>";
129"M_G_CPU0_SB_DQ<27>";
130"M_G_CPU0_SB_DQ<28>";
131"M_G_CPU0_SB_DQ<29>";
132"M_G_CPU0_SB_DQ<30>";
133"M_G_CPU0_SB_DQ<31>";
134"M_G_CPU0_SA_DQ<0>";
135"M_G_CPU0_SA_DQ<1>";
136"M_G_CPU0_SA_DQ<2>";
137"M_G_CPU0_SA_DQ<3>";
138"M_G_CPU0_SA_DQ<4>";
139"M_G_CPU0_SA_DQ<5>";
140"M_G_CPU0_SA_DQ<6>";
141"M_G_CPU0_SA_DQ<14>";
142"M_G_CPU0_SA_DQ<26>";
143"M_G_CPU0_SA_DQ<27>";
144"M_G_CPU0_SA_DQ<28>";
145"M_G_CPU0_SA_DQ<29>";
146"M_G_CPU0_SB_CS_N<1>";
147"M_G_CPU0_SA_CS_N<1>";
148"M_G_CPU0_SB_CS_N<0>";
149"M_G_CPU0_SA_CS_N<0>";
150"M_G_CPU0_CLK_DP<0>";
151"M_G_CPU0_CLK_DN<0>";
152"M_G_CPU0_SB_CB<0>";
153"M_G_CPU0_SB_CB<1>";
154"M_G_CPU0_SB_CB<2>";
155"M_G_CPU0_SB_CB<3>";
156"M_G_CPU0_SB_CB<4>";
157"M_G_CPU0_SB_CB<5>";
158"M_G_CPU0_SB_CB<6>";
159"M_G_CPU0_SA_CB<0>";
160"M_G_CPU0_SA_CB<2>";
161"M_G_CPU0_SA_CB<3>";
162"M_G_CPU0_SA_CB<5>";
163"M_G_CPU0_SA_CB<6>";
164"M_G_CPU0_SA_CA<6>";
165"M_G_CPU0_SA_CA<5>";
166"M_G_CPU0_SA_CA<4>";
167"M_G_CPU0_SA_CA<3>";
168"M_G_CPU0_SB_CA<2>";
169"M_G_CPU0_SA_CA<2>";
170"M_G_CPU0_SB_CA<1>";
171"M_G_CPU0_SA_CA<1>";
172"M_G_CPU0_SB_CA<0>";
173"M_G_CPU0_SB_CB<7>";
174"M_G_CPU0_SA_CB<1>";
175"M_G_CPU0_SA_CB<4>";
176"M_G_CPU0_SA_CB<7>";
177"PWRGD_CHGL_CPU0";
178"PD_CHG_CPU0_DIMM0_SAA";
179"GND\g";
%"TAP"
"1","(-5625,4100)","0","mstr_standard","I100";
;
CDS_LIB"mstr_standard"
BODY_TYPE"PLUMBING"
HDL_TAP"TRUE";
"B \NAC \NWC"5;
"S \NAC"
BN"5"139;
%"TAP"
"1","(-5625,4250)","0","mstr_standard","I101";
;
CDS_LIB"mstr_standard"
BODY_TYPE"PLUMBING"
HDL_TAP"TRUE";
"B \NAC \NWC"5;
"S \NAC"
BN"8"40;
%"TAP"
"1","(-5625,4300)","0","mstr_standard","I102";
;
CDS_LIB"mstr_standard"
BODY_TYPE"PLUMBING"
HDL_TAP"TRUE";
"B \NAC \NWC"5;
"S \NAC"
BN"9"39;
%"TAP"
"1","(-5625,4200)","0","mstr_standard","I103";
;
CDS_LIB"mstr_standard"
BODY_TYPE"PLUMBING"
HDL_TAP"TRUE";
"B \NAC \NWC"5;
"S \NAC"
BN"7"41;
%"TAP"
"1","(-5625,4450)","0","mstr_standard","I104";
;
CDS_LIB"mstr_standard"
BODY_TYPE"PLUMBING"
HDL_TAP"TRUE";
"B \NAC \NWC"5;
"S \NAC"
BN"12"31;
%"TAP"
"1","(-5625,4400)","0","mstr_standard","I105";
;
CDS_LIB"mstr_standard"
BODY_TYPE"PLUMBING"
HDL_TAP"TRUE";
"B \NAC \NWC"5;
"S \NAC"
BN"11"37;
%"TAP"
"1","(-5625,4350)","0","mstr_standard","I106";
;
CDS_LIB"mstr_standard"
BODY_TYPE"PLUMBING"
HDL_TAP"TRUE";
"B \NAC \NWC"5;
"S \NAC"
BN"10"38;
%"TAP"
"1","(-5625,4500)","0","mstr_standard","I107";
;
CDS_LIB"mstr_standard"
BODY_TYPE"PLUMBING"
HDL_TAP"TRUE";
"B \NAC \NWC"5;
"S \NAC"
BN"13"32;
%"TAP"
"1","(-5625,4550)","0","mstr_standard","I108";
;
CDS_LIB"mstr_standard"
BODY_TYPE"PLUMBING"
HDL_TAP"TRUE";
"B \NAC \NWC"5;
"S \NAC"
BN"14"141;
%"TAP"
"1","(-5625,4700)","0","mstr_standard","I109";
;
CDS_LIB"mstr_standard"
BODY_TYPE"PLUMBING"
HDL_TAP"TRUE";
"B \NAC \NWC"5;
"S \NAC"
BN"17"35;
%"TAP"
"1","(-5625,4650)","0","mstr_standard","I110";
;
CDS_LIB"mstr_standard"
BODY_TYPE"PLUMBING"
HDL_TAP"TRUE";
"B \NAC \NWC"5;
"S \NAC"
BN"16"34;
%"TAP"
"1","(-5625,4600)","0","mstr_standard","I111";
;
CDS_LIB"mstr_standard"
BODY_TYPE"PLUMBING"
HDL_TAP"TRUE";
"B \NAC \NWC"5;
"S \NAC"
BN"15"33;
%"TAP"
"1","(-5625,4750)","0","mstr_standard","I112";
;
CDS_LIB"mstr_standard"
BODY_TYPE"PLUMBING"
HDL_TAP"TRUE";
"B \NAC \NWC"5;
"S \NAC"
BN"18"36;
%"TAP"
"1","(-5625,4800)","0","mstr_standard","I113";
;
CDS_LIB"mstr_standard"
BODY_TYPE"PLUMBING"
HDL_TAP"TRUE";
"B \NAC \NWC"5;
"S \NAC"
BN"19"44;
%"TAP"
"1","(-5625,4950)","0","mstr_standard","I114";
;
CDS_LIB"mstr_standard"
BODY_TYPE"PLUMBING"
HDL_TAP"TRUE";
"B \NAC \NWC"5;
"S \NAC"
BN"22"85;
%"TAP"
"1","(-5625,4900)","0","mstr_standard","I115";
;
CDS_LIB"mstr_standard"
BODY_TYPE"PLUMBING"
HDL_TAP"TRUE";
"B \NAC \NWC"5;
"S \NAC"
BN"21"42;
%"TAP"
"1","(-5625,4850)","0","mstr_standard","I116";
;
CDS_LIB"mstr_standard"
BODY_TYPE"PLUMBING"
HDL_TAP"TRUE";
"B \NAC \NWC"5;
"S \NAC"
BN"20"43;
%"TAP"
"1","(-5625,5050)","0","mstr_standard","I117";
;
CDS_LIB"mstr_standard"
BODY_TYPE"PLUMBING"
HDL_TAP"TRUE";
"B \NAC \NWC"5;
"S \NAC"
BN"24"87;
%"TAP"
"1","(-5625,5000)","0","mstr_standard","I118";
;
CDS_LIB"mstr_standard"
BODY_TYPE"PLUMBING"
HDL_TAP"TRUE";
"B \NAC \NWC"5;
"S \NAC"
BN"23"86;
%"TAP"
"1","(-5625,5150)","0","mstr_standard","I119";
;
CDS_LIB"mstr_standard"
BODY_TYPE"PLUMBING"
HDL_TAP"TRUE";
"B \NAC \NWC"5;
"S \NAC"
BN"26"142;
%"TAP"
"1","(-5625,5200)","0","mstr_standard","I120";
;
CDS_LIB"mstr_standard"
BODY_TYPE"PLUMBING"
HDL_TAP"TRUE";
"B \NAC \NWC"5;
"S \NAC"
BN"27"143;
%"TAP"
"1","(-5625,5100)","0","mstr_standard","I121";
;
CDS_LIB"mstr_standard"
BODY_TYPE"PLUMBING"
HDL_TAP"TRUE";
"B \NAC \NWC"5;
"S \NAC"
BN"25"88;
%"TAP"
"1","(-5625,5350)","0","mstr_standard","I122";
;
CDS_LIB"mstr_standard"
BODY_TYPE"PLUMBING"
HDL_TAP"TRUE";
"B \NAC \NWC"5;
"S \NAC"
BN"30"89;
%"TAP"
"1","(-5625,5250)","0","mstr_standard","I123";
;
CDS_LIB"mstr_standard"
BODY_TYPE"PLUMBING"
HDL_TAP"TRUE";
"B \NAC \NWC"5;
"S \NAC"
BN"28"144;
%"TAP"
"1","(-5625,5300)","0","mstr_standard","I124";
;
CDS_LIB"mstr_standard"
BODY_TYPE"PLUMBING"
HDL_TAP"TRUE";
"B \NAC \NWC"5;
"S \NAC"
BN"29"145;
%"TAP"
"1","(-5625,5400)","0","mstr_standard","I125";
;
CDS_LIB"mstr_standard"
BODY_TYPE"PLUMBING"
HDL_TAP"TRUE";
"B \NAC \NWC"5;
"S \NAC"
BN"31"90;
%"GND"
"1","(-6025,975)","0","mstr_symbols","I128";
;
BOM_COST"MEM"
SIZE"1B"
CDS_LIB"mstr_symbols"
BODY_TYPE"PLUMBING"
VOLTAGE"0.0"
HDL_POWER"GND";
"A\NAC"10;
%"Q_RES"
"2","(-6025,1200)","0","pure_quanta","I129";
;
LOCATION"R35"
SEC"1"
WATTAGE"1/16W"
MATERIAL"CHIP"
TOLERANCE"1%"
VALUE"10K"
PART_NUMBER"CS31002FB08"
PACK_TYPE"0402LF"
SEC_TYPE"0402LF"
BOM_COST"MEM"
CDS_LIB"pure_quanta"
ROOM"MEM_CH_A_CPU0_DIMM1";
"A"
$PN"1"
XNET_PINS"3"178;
"B"
$PN"2"
XNET_PINS"2"10;
%"GND"
"1","(-1975,1900)","0","mstr_symbols","I130";
;
CDS_LIB"mstr_symbols"
SIZE"1B"
BODY_TYPE"PLUMBING"
VOLTAGE"0.0"
HDL_POWER"GND";
"A\NAC"30;
%"GND"
"1","(-375,1700)","0","mstr_symbols","I146";
;
SIZE"1B"
CDS_LIB"mstr_symbols"
BODY_TYPE"PLUMBING"
VOLTAGE"0.0"
HDL_POWER"GND";
"A\NAC"28;
%"SCONN288_DDR506112002KQ"
"3","(-1175,3650)","0","pure_quanta","I177";
;
LOCATION"J16"
$SEC"3"
CDS_SEC"3"
VALUE"SCONN288_DDR506112002KQ"
PART_TYPE"SMLF"
MATERIAL"IO"
PART_NUMBER"DFHST8FS479"
CDS_LMAN_SYM_OUTLINE"-450,1800,450,-1750"
NEEDS_NO_SIZE"TRUE"
CDS_LIB"pure_quanta";
"G3"
$PN"G3"28;
"G2"
$PN"G2"28;
"G1"
$PN"G1"28;
"VSS62"
$PN"141"28;
"VSS61"
$PN"139"28;
"VSS60"
$PN"136"28;
"VSS58"
$PN"132"28;
"VSS104"
$PN"240"30;
"VSS102"
$PN"235"30;
"VSS100"
$PN"230"30;
"VIN_BULK2"
$PN"146"29;
"VIN_BULK1"
$PN"145"29;
"VIN_BULK0"
$PN"1"29;
"VSS126"
$PN"288"30;
"VSS125"
$PN"286"30;
"VSS124"
$PN"284"30;
"VSS123"
$PN"281"30;
"VSS122"
$PN"279"30;
"VSS121"
$PN"277"30;
"VSS120"
$PN"275"30;
"VSS119"
$PN"273"30;
"VSS118"
$PN"270"30;
"VSS117"
$PN"268"30;
"VSS116"
$PN"266"30;
"VSS115"
$PN"264"30;
"VSS114"
$PN"262"30;
"VSS113"
$PN"259"30;
"VSS112"
$PN"257"30;
"VSS111"
$PN"255"30;
"VSS110"
$PN"253"30;
"VSS109"
$PN"251"30;
"VSS108"
$PN"248"30;
"VSS107"
$PN"246"30;
"VSS106"
$PN"244"30;
"VSS105"
$PN"242"30;
"VSS103"
$PN"237"30;
"VSS101"
$PN"233"30;
"VSS99"
$PN"228"30;
"VSS98"
$PN"226"30;
"VSS97"
$PN"224"30;
"VSS96"
$PN"222"30;
"VSS95"
$PN"219"30;
"VSS94"
$PN"216"30;
"VSS93"
$PN"214"30;
"VSS92"
$PN"212"30;
"VSS91"
$PN"210"30;
"VSS90"
$PN"208"30;
"VSS89"
$PN"206"30;
"VSS88"
$PN"204"30;
"VSS87"
$PN"202"30;
"VSS86"
$PN"199"30;
"VSS85"
$PN"197"30;
"VSS84"
$PN"195"30;
"VSS83"
$PN"193"30;
"VSS82"
$PN"191"30;
"VSS81"
$PN"188"30;
"VSS80"
$PN"186"30;
"VSS79"
$PN"184"30;
"VSS78"
$PN"182"30;
"VSS77"
$PN"180"30;
"VSS76"
$PN"177"30;
"VSS75"
$PN"175"30;
"VSS74"
$PN"173"30;
"VSS73"
$PN"171"30;
"VSS72"
$PN"169"30;
"VSS71"
$PN"166"30;
"VSS70"
$PN"164"30;
"VSS69"
$PN"162"30;
"VSS68"
$PN"160"30;
"VSS67"
$PN"158"30;
"VSS66"
$PN"155"30;
"VSS65"
$PN"153"30;
"VSS64"
$PN"151"30;
"VSS63"
$PN"143"28;
"VSS59"
$PN"134"28;
"VSS57"
$PN"130"28;
"VSS56"
$PN"128"28;
"VSS55"
$PN"125"28;
"VSS54"
$PN"123"28;
"VSS53"
$PN"121"28;
"VSS52"
$PN"119"28;
"VSS51"
$PN"117"28;
"VSS50"
$PN"114"28;
"VSS49"
$PN"112"28;
"VSS48"
$PN"110"28;
"VSS47"
$PN"108"28;
"VSS46"
$PN"106"28;
"VSS45"
$PN"103"28;
"VSS44"
$PN"101"28;
"VSS43"
$PN"99"28;
"VSS42"
$PN"97"28;
"VSS41"
$PN"95"28;
"VSS40"
$PN"92"28;
"VSS39"
$PN"90"28;
"VSS38"
$PN"88"28;
"VSS37"
$PN"85"28;
"VSS36"
$PN"83"28;
"VSS35"
$PN"81"28;
"VSS34"
$PN"79"28;
"VSS33"
$PN"77"28;
"VSS32"
$PN"75"28;
"VSS31"
$PN"73"28;
"VSS30"
$PN"71"28;
"VSS29"
$PN"69"28;
"VSS28"
$PN"67"28;
"VSS27"
$PN"65"28;
"VSS26"
$PN"63"28;
"VSS25"
$PN"61"28;
"VSS24"
$PN"59"28;
"VSS23"
$PN"57"28;
"VSS22"
$PN"54"28;
"VSS21"
$PN"52"28;
"VSS20"
$PN"50"28;
"VSS19"
$PN"48"28;
"VSS18"
$PN"46"28;
"VSS17"
$PN"43"28;
"VSS16"
$PN"41"28;
"VSS15"
$PN"39"28;
"VSS14"
$PN"37"28;
"VSS13"
$PN"35"28;
"VSS12"
$PN"32"28;
"VSS11"
$PN"30"28;
"VSS10"
$PN"28"28;
"VSS9"
$PN"26"28;
"VSS8"
$PN"24"28;
"VSS7"
$PN"21"28;
"VSS6"
$PN"19"28;
"VSS5"
$PN"17"28;
"VSS4"
$PN"15"28;
"VSS3"
$PN"13"28;
"VSS2"
$PN"10"28;
"VSS1"
$PN"8"28;
"VSS0"
$PN"6"28;
%"Q_CAP"
"1","(-8500,3225)","2","pure_quanta","I183";
;
LOCATION"C112"
$SEC"1"
CDS_SEC"1"
VOLTAGE"25V"
PART_NUMBER"CH4104K1B00"
PACK_TYPE"0402"
MATERIAL"X7R"
TOLERANCE"10%"
VALUE"0.1UF"
CDS_LIB"pure_quanta"
BOM_COST"MEM"
ROOM"MEM_CH_A_CPU0_DIMM1";
"B"
$PN"2"11;
"A"
$PN"1"15;
%"GND"
"1","(-8500,3000)","0","mstr_symbols","I184";
;
CDS_LIB"mstr_symbols"
SIZE"1B"
BOM_COST"MEM"
BODY_TYPE"PLUMBING"
VOLTAGE"0"
ROOM"MEM_EFGH_DECOUPLING_CAPS"
HDL_POWER"GND";
"A\NAC"11;
%"Q_RES"
"1","(-8350,2150)","2","pure_quanta","I186";
;
LOCATION"R297"
$SEC"1"
CDS_SEC"1"
VALUE"0"
CDS_LIB"pure_quanta"
BOM_COST"MEM"
WATTAGE"1/16W"
MATERIAL"CHIP"
TOLERANCE"5%"
PART_NUMBER"CS00002JB38"
PACK_TYPE"0402LF"
ROOM"RST_CPU0_PLD_TO_DIMM";
"B"
$PN"2"177;
"A"
$PN"1"21;
%"Q_RES"
"2","(-8225,2300)","0","pure_quanta","I187";
;
LOCATION"R96"
$SEC"1"
CDS_SEC"1"
WATTAGE"1/16W"
MATERIAL"EMPTY"
TOLERANCE"5%"
VALUE"1K"
PACK_TYPE"0402LF"
CDS_LIB"pure_quanta"
BOM_COST"MEM"
PART_NUMBER"TMP_QCS21002JB34"
ROOM"MEM_CH_A_CPU0_DIMM1";
"A"
$PN"1"12;
"B"
$PN"2"21;
%"VCC_CORE"
"1","(-8225,2475)","0","mstr_symbols","I188";
;
HDL_POWER"P3V3_STBY"
CDS_LIB"mstr_symbols"
VOLTAGE"3.3"
ROOM"PVCCINFAON_CPU0_CTRL";
"A"12;
%"VCC_CORE"
"1","(-8475,2475)","0","mstr_symbols","I189";
;
HDL_POWER"P3V3_STBY"
CDS_LIB"mstr_symbols"
VOLTAGE"3.3"
ROOM"PVCCINFAON_CPU0_CTRL";
"A"13;
%"Q_RES"
"2","(-8475,2300)","2","pure_quanta","I190";
;
LOCATION"R95"
$SEC"1"
CDS_SEC"1"
WATTAGE"1/16W"
MATERIAL"CHIP"
TOLERANCE"5%"
VALUE"1K"
PACK_TYPE"0402LF"
PART_NUMBER"TMP_QCS21002JB34"
BOM_COST"MEM"
CDS_LIB"pure_quanta"
ROOM"MEM_CH_A_CPU0_DIMM1";
"A"
$PN"1"13;
"B"
$PN"2"177;
%"TAP"
"1","(-2900,4525)","0","mstr_standard","I196";
;
CDS_LIB"mstr_standard"
BODY_TYPE"PLUMBING"
HDL_TAP"TRUE";
"B \NAC \NWC"14;
"S \NAC"
BN"9"48;
%"TAP"
"1","(-2900,4425)","0","mstr_standard","I197";
;
CDS_LIB"mstr_standard"
BODY_TYPE"PLUMBING"
HDL_TAP"TRUE";
"B \NAC \NWC"14;
"S \NAC"
BN"8"50;
%"TAP"
"1","(-3100,4575)","0","mstr_standard","I198";
;
CDS_LIB"mstr_standard"
BODY_TYPE"PLUMBING"
HDL_TAP"TRUE";
"B \NAC \NWC"7;
"S \NAC"
BN"9"47;
%"TAP"
"1","(-3100,4475)","0","mstr_standard","I199";
;
CDS_LIB"mstr_standard"
BODY_TYPE"PLUMBING"
HDL_TAP"TRUE";
"B \NAC \NWC"7;
"S \NAC"
BN"8"49;
%"TAP"
"1","(-3100,4375)","0","mstr_standard","I200";
;
CDS_LIB"mstr_standard"
BODY_TYPE"PLUMBING"
HDL_TAP"TRUE";
"B \NAC \NWC"7;
"S \NAC"
BN"7"52;
%"TAP"
"1","(-2900,4325)","0","mstr_standard","I201";
;
CDS_LIB"mstr_standard"
BODY_TYPE"PLUMBING"
HDL_TAP"TRUE";
"B \NAC \NWC"14;
"S \NAC"
BN"7"84;
%"TAP"
"1","(-2900,4125)","0","mstr_standard","I202";
;
CDS_LIB"mstr_standard"
BODY_TYPE"PLUMBING"
HDL_TAP"TRUE";
"B \NAC \NWC"14;
"S \NAC"
BN"5"59;
%"TAP"
"1","(-2900,4225)","0","mstr_standard","I203";
;
CDS_LIB"mstr_standard"
BODY_TYPE"PLUMBING"
HDL_TAP"TRUE";
"B \NAC \NWC"14;
"S \NAC"
BN"6"55;
%"TAP"
"1","(-2900,4025)","0","mstr_standard","I204";
;
CDS_LIB"mstr_standard"
BODY_TYPE"PLUMBING"
HDL_TAP"TRUE";
"B \NAC \NWC"14;
"S \NAC"
BN"4"63;
%"TAP"
"1","(-2900,3925)","0","mstr_standard","I205";
;
CDS_LIB"mstr_standard"
BODY_TYPE"PLUMBING"
HDL_TAP"TRUE";
"B \NAC \NWC"14;
"S \NAC"
BN"3"67;
%"TAP"
"1","(-3100,4175)","0","mstr_standard","I206";
;
CDS_LIB"mstr_standard"
BODY_TYPE"PLUMBING"
HDL_TAP"TRUE";
"B \NAC \NWC"7;
"S \NAC"
BN"5"58;
%"TAP"
"1","(-3100,4275)","0","mstr_standard","I207";
;
CDS_LIB"mstr_standard"
BODY_TYPE"PLUMBING"
HDL_TAP"TRUE";
"B \NAC \NWC"7;
"S \NAC"
BN"6"83;
%"TAP"
"1","(-3100,4075)","0","mstr_standard","I208";
;
CDS_LIB"mstr_standard"
BODY_TYPE"PLUMBING"
HDL_TAP"TRUE";
"B \NAC \NWC"7;
"S \NAC"
BN"4"62;
%"TAP"
"1","(-3100,3875)","0","mstr_standard","I209";
;
CDS_LIB"mstr_standard"
BODY_TYPE"PLUMBING"
HDL_TAP"TRUE";
"B \NAC \NWC"7;
"S \NAC"
BN"2"70;
%"TAP"
"1","(-3100,3975)","0","mstr_standard","I210";
;
CDS_LIB"mstr_standard"
BODY_TYPE"PLUMBING"
HDL_TAP"TRUE";
"B \NAC \NWC"7;
"S \NAC"
BN"3"66;
%"TAP"
"1","(-2900,3825)","0","mstr_standard","I211";
;
CDS_LIB"mstr_standard"
BODY_TYPE"PLUMBING"
HDL_TAP"TRUE";
"B \NAC \NWC"14;
"S \NAC"
BN"2"71;
%"TAP"
"1","(-2900,3725)","0","mstr_standard","I212";
;
CDS_LIB"mstr_standard"
BODY_TYPE"PLUMBING"
HDL_TAP"TRUE";
"B \NAC \NWC"14;
"S \NAC"
BN"1"75;
%"TAP"
"1","(-2900,3625)","0","mstr_standard","I213";
;
CDS_LIB"mstr_standard"
BODY_TYPE"PLUMBING"
HDL_TAP"TRUE";
"B \NAC \NWC"14;
"S \NAC"
BN"0"79;
%"TAP"
"1","(-2900,3475)","0","mstr_standard","I214";
;
CDS_LIB"mstr_standard"
BODY_TYPE"PLUMBING"
HDL_TAP"TRUE";
"B \NAC \NWC"8;
"S \NAC"
BN"9"46;
%"TAP"
"1","(-2900,3375)","0","mstr_standard","I215";
;
CDS_LIB"mstr_standard"
BODY_TYPE"PLUMBING"
HDL_TAP"TRUE";
"B \NAC \NWC"8;
"S \NAC"
BN"8"81;
%"TAP"
"1","(-3100,3675)","0","mstr_standard","I216";
;
CDS_LIB"mstr_standard"
BODY_TYPE"PLUMBING"
HDL_TAP"TRUE";
"B \NAC \NWC"7;
"S \NAC"
BN"0"78;
%"TAP"
"1","(-3100,3775)","0","mstr_standard","I217";
;
CDS_LIB"mstr_standard"
BODY_TYPE"PLUMBING"
HDL_TAP"TRUE";
"B \NAC \NWC"7;
"S \NAC"
BN"1"74;
%"TAP"
"1","(-3100,3425)","0","mstr_standard","I218";
;
CDS_LIB"mstr_standard"
BODY_TYPE"PLUMBING"
HDL_TAP"TRUE";
"B \NAC \NWC"9;
"S \NAC"
BN"8"82;
%"TAP"
"1","(-3100,3525)","0","mstr_standard","I219";
;
CDS_LIB"mstr_standard"
BODY_TYPE"PLUMBING"
HDL_TAP"TRUE";
"B \NAC \NWC"9;
"S \NAC"
BN"9"45;
%"SCONN288_DDR506112002KQ"
"1","(-6475,3650)","0","pure_quanta","I22";
;
LOCATION"J16"
$SEC"1"
CDS_SEC"1"
MATERIAL"IO"
PART_NUMBER"DFHST8FS479"
PART_TYPE"SMLF"
VALUE"SCONN288_DDR506112002KQ"
CDS_LMAN_SYM_OUTLINE"-450,1900,450,-1850"
NEEDS_NO_SIZE"TRUE"
CDS_LIB"pure_quanta";
"PWR_GOOD||FAIL_N"
$PN"147"21;
"DQ31_A"
$PN"194"90;
"CB7_A"
$PN"205"176;
"CB4_A"
$PN"58"175;
"CB1_A"
$PN"53"174;
"CB7_B"
$PN"236"173;
"ALERT_N \B"
$PN"62"20;
"CA0_A"
$PN"66"23;
"CA0_B"
$PN"76"172;
"CA1_A"
$PN"211"171;
"CA1_B"
$PN"221"170;
"CA2_A"
$PN"68"169;
"CA2_B"
$PN"78"168;
"CA3_A"
$PN"213"167;
"CA3_B"
$PN"223"27;
"CA4_A"
$PN"70"166;
"CA4_B"
$PN"80"26;
"CA5_A"
$PN"215"165;
"CA5_B"
$PN"225"25;
"CA6_A"
$PN"72"164;
"CA6_B"
$PN"82"24;
"CB6_A"
$PN"203"163;
"CB5_A"
$PN"60"162;
"CB3_A"
$PN"198"161;
"CB2_A"
$PN"196"160;
"CB0_A"
$PN"51"159;
"CB6_B"
$PN"234"158;
"CB5_B"
$PN"91"157;
"CB4_B"
$PN"89"156;
"CB3_B"
$PN"243"155;
"CB2_B"
$PN"241"154;
"CB1_B"
$PN"98"153;
"CB0_B"
$PN"96"152;
"CK_C \B"
$PN"218"151;
"CK_T"
$PN"217"150;
"CS0_A_N"
$PN"64"149;
"CS0_B_N"
$PN"84"148;
"CS1_A_N"
$PN"209"147;
"CS1_B_N"
$PN"229"146;
"DQ30_A"
$PN"192"89;
"DQ29_A"
$PN"49"145;
"DQ28_A"
$PN"47"144;
"DQ27_A"
$PN"187"143;
"DQ26_A"
$PN"185"142;
"DQ25_A"
$PN"42"88;
"DQ24_A"
$PN"40"87;
"DQ23_A"
$PN"183"86;
"DQ22_A"
$PN"181"85;
"DQ21_A"
$PN"38"42;
"DQ20_A"
$PN"36"43;
"DQ19_A"
$PN"176"44;
"DQ18_A"
$PN"174"36;
"DQ17_A"
$PN"31"35;
"DQ16_A"
$PN"29"34;
"DQ15_A"
$PN"172"33;
"DQ14_A"
$PN"170"141;
"DQ13_A"
$PN"27"32;
"DQ12_A"
$PN"25"31;
"DQ11_A"
$PN"165"37;
"DQ10_A"
$PN"163"38;
"DQ9_A"
$PN"20"39;
"DQ8_A"
$PN"18"40;
"DQ7_A"
$PN"161"41;
"DQ6_A"
$PN"159"140;
"DQ5_A"
$PN"16"139;
"DQ4_A"
$PN"14"138;
"DQ3_A"
$PN"154"137;
"DQ2_A"
$PN"152"136;
"DQ1_A"
$PN"9"135;
"DQ0_A"
$PN"7"134;
"DQ31_B"
$PN"287"133;
"DQ30_B"
$PN"285"132;
"DQ29_B"
$PN"142"131;
"DQ28_B"
$PN"140"130;
"DQ27_B"
$PN"280"129;
"DQ26_B"
$PN"278"128;
"DQ25_B"
$PN"135"127;
"DQ24_B"
$PN"133"126;
"DQ23_B"
$PN"276"125;
"DQ22_B"
$PN"274"124;
"DQ21_B"
$PN"131"123;
"DQ20_B"
$PN"129"122;
"DQ19_B"
$PN"269"121;
"DQ18_B"
$PN"267"120;
"DQ17_B"
$PN"124"119;
"DQ16_B"
$PN"122"118;
"DQ15_B"
$PN"265"117;
"DQ14_B"
$PN"263"116;
"DQ13_B"
$PN"120"115;
"DQ12_B"
$PN"118"114;
"DQ11_B"
$PN"258"113;
"DQ10_B"
$PN"256"112;
"DQ9_B"
$PN"113"111;
"DQ8_B"
$PN"111"110;
"DQ7_B"
$PN"254"109;
"DQ6_B"
$PN"252"108;
"DQ5_B"
$PN"109"107;
"DQ4_B"
$PN"107"106;
"DQ3_B"
$PN"247"105;
"DQ2_B"
$PN"245"104;
"DQ1_B"
$PN"102"103;
"DQ0_B"
$PN"100"102;
"HAS"
$PN"148"16;
"HSCL"
$PN"4"18;
"HSDA"
$PN"5"17;
"LBD||RSP_A_N"
$PN"86"101;
"LBS||RSP_B_N"
$PN"87"100;
"PAR_A"
$PN"74"99;
"PAR_B"
$PN"227"98;
"RESET_N \B"
$PN"207"22;
"RFU6"
$PN"232"97;
"RFU5"
$PN"231"96;
"RFU4"
$PN"220"95;
"RFU3"
$PN"150"94;
"RFU2"
$PN"149"93;
"RFU1"
$PN"144"92;
"RFU0"
$PN"2"91;
"VIN_MGMT"
$PN"3"15;
%"TAP"
"1","(-2900,3275)","0","mstr_standard","I220";
;
CDS_LIB"mstr_standard"
BODY_TYPE"PLUMBING"
HDL_TAP"TRUE";
"B \NAC \NWC"8;
"S \NAC"
BN"7"51;
%"TAP"
"1","(-2900,3175)","0","mstr_standard","I221";
;
CDS_LIB"mstr_standard"
BODY_TYPE"PLUMBING"
HDL_TAP"TRUE";
"B \NAC \NWC"8;
"S \NAC"
BN"6"54;
%"TAP"
"1","(-2900,3075)","0","mstr_standard","I222";
;
CDS_LIB"mstr_standard"
BODY_TYPE"PLUMBING"
HDL_TAP"TRUE";
"B \NAC \NWC"8;
"S \NAC"
BN"5"57;
%"TAP"
"1","(-2900,2975)","0","mstr_standard","I223";
;
CDS_LIB"mstr_standard"
BODY_TYPE"PLUMBING"
HDL_TAP"TRUE";
"B \NAC \NWC"8;
"S \NAC"
BN"4"61;
%"TAP"
"1","(-2900,2875)","0","mstr_standard","I224";
;
CDS_LIB"mstr_standard"
BODY_TYPE"PLUMBING"
HDL_TAP"TRUE";
"B \NAC \NWC"8;
"S \NAC"
BN"3"65;
%"TAP"
"1","(-3100,3225)","0","mstr_standard","I225";
;
CDS_LIB"mstr_standard"
BODY_TYPE"PLUMBING"
HDL_TAP"TRUE";
"B \NAC \NWC"9;
"S \NAC"
BN"6"53;
%"TAP"
"1","(-3100,3325)","0","mstr_standard","I226";
;
CDS_LIB"mstr_standard"
BODY_TYPE"PLUMBING"
HDL_TAP"TRUE";
"B \NAC \NWC"9;
"S \NAC"
BN"7"80;
%"TAP"
"1","(-3100,3125)","0","mstr_standard","I227";
;
CDS_LIB"mstr_standard"
BODY_TYPE"PLUMBING"
HDL_TAP"TRUE";
"B \NAC \NWC"9;
"S \NAC"
BN"5"56;
%"TAP"
"1","(-3100,3025)","0","mstr_standard","I228";
;
CDS_LIB"mstr_standard"
BODY_TYPE"PLUMBING"
HDL_TAP"TRUE";
"B \NAC \NWC"9;
"S \NAC"
BN"4"60;
%"TAP"
"1","(-3100,2925)","0","mstr_standard","I229";
;
CDS_LIB"mstr_standard"
BODY_TYPE"PLUMBING"
HDL_TAP"TRUE";
"B \NAC \NWC"9;
"S \NAC"
BN"3"64;
%"TAP"
"1","(-7325,3200)","2","mstr_standard","I23";
;
CDS_LIB"mstr_standard"
BODY_TYPE"PLUMBING"
HDL_TAP"TRUE";
"B \NAC \NWC"4;
"S \NAC"
BN"0"152;
%"TAP"
"1","(-2900,2775)","0","mstr_standard","I230";
;
CDS_LIB"mstr_standard"
BODY_TYPE"PLUMBING"
HDL_TAP"TRUE";
"B \NAC \NWC"8;
"S \NAC"
BN"2"69;
%"TAP"
"1","(-2900,2675)","0","mstr_standard","I231";
;
CDS_LIB"mstr_standard"
BODY_TYPE"PLUMBING"
HDL_TAP"TRUE";
"B \NAC \NWC"8;
"S \NAC"
BN"1"73;
%"TAP"
"1","(-2900,2575)","0","mstr_standard","I232";
;
CDS_LIB"mstr_standard"
BODY_TYPE"PLUMBING"
HDL_TAP"TRUE";
"B \NAC \NWC"8;
"S \NAC"
BN"0"77;
%"TAP"
"1","(-3100,2625)","0","mstr_standard","I233";
;
CDS_LIB"mstr_standard"
BODY_TYPE"PLUMBING"
HDL_TAP"TRUE";
"B \NAC \NWC"9;
"S \NAC"
BN"0"76;
%"TAP"
"1","(-3100,2725)","0","mstr_standard","I234";
;
CDS_LIB"mstr_standard"
BODY_TYPE"PLUMBING"
HDL_TAP"TRUE";
"B \NAC \NWC"9;
"S \NAC"
BN"1"72;
%"TAP"
"1","(-3100,2825)","0","mstr_standard","I235";
;
CDS_LIB"mstr_standard"
BODY_TYPE"PLUMBING"
HDL_TAP"TRUE";
"B \NAC \NWC"9;
"S \NAC"
BN"2"68;
%"SCONN288_DDR506112002KQ"
"2","(-4100,3575)","0","pure_quanta","I236";
;
LOCATION"J16"
$SEC"2"
CDS_SEC"2"
PART_TYPE"SMLF"
VALUE"SCONN288_DDR506112002KQ"
MATERIAL"IO"
PART_NUMBER"DFHST8FS479"
CDS_LMAN_SYM_OUTLINE"-600,1150,600,-1150"
NEEDS_NO_SIZE"TRUE"
CDS_LIB"pure_quanta";
"DQS7_A_C||TDQS7_A_C \B"
$PN"178"84;
"DQS6_A_T||TDQS6_A_T"
$PN"168"83;
"DQS8_B_T||TDQS8_B_T"
$PN"283"82;
"DQS8_B_C||TDQS8_B_C \B"
$PN"282"81;
"DQS7_B_T||TDQS7_B_T"
$PN"272"80;
"DQS0_A_C \B"
$PN"12"79;
"DQS0_A_T"
$PN"11"78;
"DQS0_B_C \B"
$PN"105"77;
"DQS0_B_T"
$PN"104"76;
"DQS1_A_C \B"
$PN"23"75;
"DQS1_A_T"
$PN"22"74;
"DQS1_B_C \B"
$PN"116"73;
"DQS1_B_T"
$PN"115"72;
"DQS2_A_C \B"
$PN"34"71;
"DQS2_A_T"
$PN"33"70;
"DQS2_B_C \B"
$PN"127"69;
"DQS2_B_T"
$PN"126"68;
"DQS3_A_C \B"
$PN"45"67;
"DQS3_A_T"
$PN"44"66;
"DQS3_B_C \B"
$PN"138"65;
"DQS3_B_T"
$PN"137"64;
"DQS4_A_C \B"
$PN"56"63;
"DQS4_A_T"
$PN"55"62;
"DQS4_B_C \B"
$PN"238"61;
"DQS4_B_T"
$PN"239"60;
"DQS5_A_C||TDQS5_A_C||DQS5_A_T||TDQS5_A_T \B"
$PN"156"59;
"DQS5_A_T||TDQS5_A_T"
$PN"157"58;
"DQS5_B_C||TDQS5_B_C \B"
$PN"249"57;
"DQS5_B_T||TDQS5_B_T"
$PN"250"56;
"DQS6_A_C||TDQS6_A_C||DQS6_A_T||TDQS6_A_T \B"
$PN"167"55;
"DQS6_B_C||TDQS6_B_C \B"
$PN"260"54;
"DQS6_B_T||TDQS6_B_T"
$PN"261"53;
"DQS7_A_T||TDQS7_A_T"
$PN"179"52;
"DQS7_B_C||TDQS7_B_C \B"
$PN"271"51;
"DQS8_A_C||TDQS8_A_C \B"
$PN"189"50;
"DQS8_A_T||TDQS8_A_T"
$PN"190"49;
"DQS9_A_C||TDQS9_A_C \B"
$PN"200"48;
"DQS9_A_T||TDQS9_A_T"
$PN"201"47;
"DQS9_B_C||TDQS9_B_C \B"
$PN"94"46;
"DQS9_B_T||TDQS9_B_T||DBI4_B_N"
$PN"93"45;
%"GND"
"1","(-2675,5525)","0","pure_quanta_power","I237";
;
CDS_LIB"pure_quanta_power"
BOM_COST"MEM"
SIZE"1B"
ROOM"MEM_EFGH_DECOUPLING_CAPS"
HDL_POWER"GND";
"A<SIZE-1..0>\NAC"179;
%"Q_CAP"
"1","(-2675,5875)","2","pure_quanta","I238";
;
LOCATION"C157"
$SEC"1"
CDS_SEC"1"
MATERIAL"X6S"
TOLERANCE"10%"
VALUE"10UF"
PART_NUMBER"CH6104KEA00"
VOLTAGE"25V"
PACK_TYPE"C0805"
BOM_COST"MEM"
CDS_LIB"pure_quanta"
ROOM"MEM_CH_A_CPU0_DIMM1";
"B"
$PN"2"179;
"A"
$PN"1"29;
%"Q_CAP"
"1","(-2100,5875)","2","pure_quanta","I239";
;
LOCATION"C158"
$SEC"1"
CDS_SEC"1"
MATERIAL"X6S"
TOLERANCE"10%"
VALUE"10UF"
VOLTAGE"25V"
PACK_TYPE"C0805"
PART_NUMBER"CH6104KEA00"
BOM_COST"MEM"
CDS_LIB"pure_quanta"
ROOM"MEM_CH_A_CPU0_DIMM1";
"B"
$PN"2"179;
"A"
$PN"1"29;
%"TAP"
"1","(-7325,3250)","2","mstr_standard","I24";
;
CDS_LIB"mstr_standard"
BODY_TYPE"PLUMBING"
HDL_TAP"TRUE";
"B \NAC \NWC"4;
"S \NAC"
BN"1"153;
%"UNIVERSAL_POWER"
"1","(-2675,6200)","0","pure_quanta_power","I240";
;
HDL_POWER"P12V_MEM_0"
CDS_LIB"pure_quanta_power"
BOM_COST"VR_SYSTEM";
"A"29;
%"Q_RES"
"1","(-7375,2700)","0","pure_quanta","I242";
;
$LOCATION"R1574"
CDS_LOCATION"R1574"
$SEC"1"
CDS_SEC"1"
VALUE"49.9"
CDS_LIB"pure_quanta"
MATERIAL"CHIP"
PACK_TYPE"0402LF"
WATTAGE"1/16W"
TOLERANCE"1%"
PART_NUMBER"CS04992FB07";
"B"
$PN"2"18;
"A"
$PN"1"19;
%"TAP"
"1","(-7325,3300)","2","mstr_standard","I25";
;
CDS_LIB"mstr_standard"
BODY_TYPE"PLUMBING"
HDL_TAP"TRUE";
"B \NAC \NWC"4;
"S \NAC"
BN"2"154;
%"TAP"
"1","(-7325,3350)","2","mstr_standard","I26";
;
CDS_LIB"mstr_standard"
BODY_TYPE"PLUMBING"
HDL_TAP"TRUE";
"B \NAC \NWC"4;
"S \NAC"
BN"3"155;
%"TAP"
"1","(-7325,3400)","2","mstr_standard","I27";
;
CDS_LIB"mstr_standard"
BODY_TYPE"PLUMBING"
HDL_TAP"TRUE";
"B \NAC \NWC"4;
"S \NAC"
BN"4"156;
%"TAP"
"1","(-7325,3450)","2","mstr_standard","I28";
;
CDS_LIB"mstr_standard"
BODY_TYPE"PLUMBING"
HDL_TAP"TRUE";
"B \NAC \NWC"4;
"S \NAC"
BN"5"157;
%"TAP"
"1","(-7325,3500)","2","mstr_standard","I29";
;
CDS_LIB"mstr_standard"
BODY_TYPE"PLUMBING"
HDL_TAP"TRUE";
"B \NAC \NWC"4;
"S \NAC"
BN"6"158;
%"TAP"
"1","(-7325,3550)","2","mstr_standard","I30";
;
CDS_LIB"mstr_standard"
BODY_TYPE"PLUMBING"
HDL_TAP"TRUE";
"B \NAC \NWC"4;
"S \NAC"
BN"7"173;
%"TAP"
"1","(-7325,3650)","2","mstr_standard","I31";
;
CDS_LIB"mstr_standard"
BODY_TYPE"PLUMBING"
HDL_TAP"TRUE";
"B \NAC \NWC"1;
"S \NAC"
BN"0"159;
%"TAP"
"1","(-7325,3700)","2","mstr_standard","I32";
;
CDS_LIB"mstr_standard"
BODY_TYPE"PLUMBING"
HDL_TAP"TRUE";
"B \NAC \NWC"1;
"S \NAC"
BN"1"174;
%"TAP"
"1","(-7325,3750)","2","mstr_standard","I33";
;
CDS_LIB"mstr_standard"
BODY_TYPE"PLUMBING"
HDL_TAP"TRUE";
"B \NAC \NWC"1;
"S \NAC"
BN"2"160;
%"TAP"
"1","(-7325,3800)","2","mstr_standard","I34";
;
CDS_LIB"mstr_standard"
BODY_TYPE"PLUMBING"
HDL_TAP"TRUE";
"B \NAC \NWC"1;
"S \NAC"
BN"3"161;
%"TAP"
"1","(-7325,3850)","2","mstr_standard","I35";
;
CDS_LIB"mstr_standard"
BODY_TYPE"PLUMBING"
HDL_TAP"TRUE";
"B \NAC \NWC"1;
"S \NAC"
BN"4"175;
%"TAP"
"1","(-7325,3900)","2","mstr_standard","I36";
;
CDS_LIB"mstr_standard"
BODY_TYPE"PLUMBING"
HDL_TAP"TRUE";
"B \NAC \NWC"1;
"S \NAC"
BN"5"162;
%"TAP"
"1","(-7325,3950)","2","mstr_standard","I37";
;
CDS_LIB"mstr_standard"
BODY_TYPE"PLUMBING"
HDL_TAP"TRUE";
"B \NAC \NWC"1;
"S \NAC"
BN"6"163;
%"TAP"
"1","(-7325,4000)","2","mstr_standard","I38";
;
CDS_LIB"mstr_standard"
BODY_TYPE"PLUMBING"
HDL_TAP"TRUE";
"B \NAC \NWC"1;
"S \NAC"
BN"7"176;
%"TAP"
"1","(-5625,2250)","0","mstr_standard","I46";
;
CDS_LIB"mstr_standard"
BODY_TYPE"PLUMBING"
HDL_TAP"TRUE";
"B \NAC \NWC"6;
"S \NAC"
BN"1"103;
%"TAP"
"1","(-5625,2200)","0","mstr_standard","I47";
;
CDS_LIB"mstr_standard"
BODY_TYPE"PLUMBING"
HDL_TAP"TRUE";
"B \NAC \NWC"6;
"S \NAC"
BN"0"102;
%"TAP"
"1","(-5625,2400)","0","mstr_standard","I48";
;
CDS_LIB"mstr_standard"
BODY_TYPE"PLUMBING"
HDL_TAP"TRUE";
"B \NAC \NWC"6;
"S \NAC"
BN"4"106;
%"TAP"
"1","(-5625,2350)","0","mstr_standard","I49";
;
CDS_LIB"mstr_standard"
BODY_TYPE"PLUMBING"
HDL_TAP"TRUE";
"B \NAC \NWC"6;
"S \NAC"
BN"3"105;
%"TAP"
"1","(-5625,2300)","0","mstr_standard","I50";
;
CDS_LIB"mstr_standard"
BODY_TYPE"PLUMBING"
HDL_TAP"TRUE";
"B \NAC \NWC"6;
"S \NAC"
BN"2"104;
%"TAP"
"1","(-5625,2450)","0","mstr_standard","I51";
;
CDS_LIB"mstr_standard"
BODY_TYPE"PLUMBING"
HDL_TAP"TRUE";
"B \NAC \NWC"6;
"S \NAC"
BN"5"107;
%"TAP"
"1","(-5625,2500)","0","mstr_standard","I52";
;
CDS_LIB"mstr_standard"
BODY_TYPE"PLUMBING"
HDL_TAP"TRUE";
"B \NAC \NWC"6;
"S \NAC"
BN"6"108;
%"TAP"
"1","(-5625,2650)","0","mstr_standard","I53";
;
CDS_LIB"mstr_standard"
BODY_TYPE"PLUMBING"
HDL_TAP"TRUE";
"B \NAC \NWC"6;
"S \NAC"
BN"9"111;
%"TAP"
"1","(-5625,2600)","0","mstr_standard","I54";
;
CDS_LIB"mstr_standard"
BODY_TYPE"PLUMBING"
HDL_TAP"TRUE";
"B \NAC \NWC"6;
"S \NAC"
BN"8"110;
%"TAP"
"1","(-5625,2550)","0","mstr_standard","I55";
;
CDS_LIB"mstr_standard"
BODY_TYPE"PLUMBING"
HDL_TAP"TRUE";
"B \NAC \NWC"6;
"S \NAC"
BN"7"109;
%"TAP"
"1","(-5625,2700)","0","mstr_standard","I56";
;
CDS_LIB"mstr_standard"
BODY_TYPE"PLUMBING"
HDL_TAP"TRUE";
"B \NAC \NWC"6;
"S \NAC"
BN"10"112;
%"TAP"
"1","(-5625,2750)","0","mstr_standard","I57";
;
CDS_LIB"mstr_standard"
BODY_TYPE"PLUMBING"
HDL_TAP"TRUE";
"B \NAC \NWC"6;
"S \NAC"
BN"11"113;
%"TAP"
"1","(-5625,2900)","0","mstr_standard","I58";
;
CDS_LIB"mstr_standard"
BODY_TYPE"PLUMBING"
HDL_TAP"TRUE";
"B \NAC \NWC"6;
"S \NAC"
BN"14"116;
%"TAP"
"1","(-5625,2850)","0","mstr_standard","I59";
;
CDS_LIB"mstr_standard"
BODY_TYPE"PLUMBING"
HDL_TAP"TRUE";
"B \NAC \NWC"6;
"S \NAC"
BN"13"115;
%"TAP"
"1","(-5625,2800)","0","mstr_standard","I60";
;
CDS_LIB"mstr_standard"
BODY_TYPE"PLUMBING"
HDL_TAP"TRUE";
"B \NAC \NWC"6;
"S \NAC"
BN"12"114;
%"TAP"
"1","(-5625,3000)","0","mstr_standard","I61";
;
CDS_LIB"mstr_standard"
BODY_TYPE"PLUMBING"
HDL_TAP"TRUE";
"B \NAC \NWC"6;
"S \NAC"
BN"16"118;
%"TAP"
"1","(-5625,2950)","0","mstr_standard","I62";
;
CDS_LIB"mstr_standard"
BODY_TYPE"PLUMBING"
HDL_TAP"TRUE";
"B \NAC \NWC"6;
"S \NAC"
BN"15"117;
%"TAP"
"1","(-5625,3050)","0","mstr_standard","I63";
;
CDS_LIB"mstr_standard"
BODY_TYPE"PLUMBING"
HDL_TAP"TRUE";
"B \NAC \NWC"6;
"S \NAC"
BN"17"119;
%"TAP"
"1","(-5625,3150)","0","mstr_standard","I64";
;
CDS_LIB"mstr_standard"
BODY_TYPE"PLUMBING"
HDL_TAP"TRUE";
"B \NAC \NWC"6;
"S \NAC"
BN"19"121;
%"TAP"
"1","(-5625,3100)","0","mstr_standard","I65";
;
CDS_LIB"mstr_standard"
BODY_TYPE"PLUMBING"
HDL_TAP"TRUE";
"B \NAC \NWC"6;
"S \NAC"
BN"18"120;
%"TAP"
"1","(-5625,3200)","0","mstr_standard","I66";
;
CDS_LIB"mstr_standard"
BODY_TYPE"PLUMBING"
HDL_TAP"TRUE";
"B \NAC \NWC"6;
"S \NAC"
BN"20"122;
%"TAP"
"1","(-5625,3250)","0","mstr_standard","I67";
;
CDS_LIB"mstr_standard"
BODY_TYPE"PLUMBING"
HDL_TAP"TRUE";
"B \NAC \NWC"6;
"S \NAC"
BN"21"123;
%"TAP"
"1","(-5625,3300)","0","mstr_standard","I68";
;
CDS_LIB"mstr_standard"
BODY_TYPE"PLUMBING"
HDL_TAP"TRUE";
"B \NAC \NWC"6;
"S \NAC"
BN"22"124;
%"TAP"
"1","(-5625,3400)","0","mstr_standard","I69";
;
CDS_LIB"mstr_standard"
BODY_TYPE"PLUMBING"
HDL_TAP"TRUE";
"B \NAC \NWC"6;
"S \NAC"
BN"24"126;
%"TAP"
"1","(-5625,3350)","0","mstr_standard","I70";
;
CDS_LIB"mstr_standard"
BODY_TYPE"PLUMBING"
HDL_TAP"TRUE";
"B \NAC \NWC"6;
"S \NAC"
BN"23"125;
%"TAP"
"1","(-5625,3450)","0","mstr_standard","I71";
;
CDS_LIB"mstr_standard"
BODY_TYPE"PLUMBING"
HDL_TAP"TRUE";
"B \NAC \NWC"6;
"S \NAC"
BN"25"127;
%"TAP"
"1","(-5625,3500)","0","mstr_standard","I72";
;
CDS_LIB"mstr_standard"
BODY_TYPE"PLUMBING"
HDL_TAP"TRUE";
"B \NAC \NWC"6;
"S \NAC"
BN"26"128;
%"TAP"
"1","(-5625,3550)","0","mstr_standard","I73";
;
CDS_LIB"mstr_standard"
BODY_TYPE"PLUMBING"
HDL_TAP"TRUE";
"B \NAC \NWC"6;
"S \NAC"
BN"27"129;
%"TAP"
"1","(-5625,3650)","0","mstr_standard","I74";
;
CDS_LIB"mstr_standard"
BODY_TYPE"PLUMBING"
HDL_TAP"TRUE";
"B \NAC \NWC"6;
"S \NAC"
BN"29"131;
%"TAP"
"1","(-5625,3600)","0","mstr_standard","I75";
;
CDS_LIB"mstr_standard"
BODY_TYPE"PLUMBING"
HDL_TAP"TRUE";
"B \NAC \NWC"6;
"S \NAC"
BN"28"130;
%"TAP"
"1","(-5625,3700)","0","mstr_standard","I76";
;
CDS_LIB"mstr_standard"
BODY_TYPE"PLUMBING"
HDL_TAP"TRUE";
"B \NAC \NWC"6;
"S \NAC"
BN"30"132;
%"TAP"
"1","(-5625,3750)","0","mstr_standard","I77";
;
CDS_LIB"mstr_standard"
BODY_TYPE"PLUMBING"
HDL_TAP"TRUE";
"B \NAC \NWC"6;
"S \NAC"
BN"31"133;
%"TAP"
"1","(-5625,3900)","0","mstr_standard","I78";
;
CDS_LIB"mstr_standard"
BODY_TYPE"PLUMBING"
HDL_TAP"TRUE";
"B \NAC \NWC"5;
"S \NAC"
BN"1"135;
%"TAP"
"1","(-5625,3850)","0","mstr_standard","I79";
;
CDS_LIB"mstr_standard"
BODY_TYPE"PLUMBING"
HDL_TAP"TRUE";
"B \NAC \NWC"5;
"S \NAC"
BN"0"134;
%"VCC_CORE"
"1","(-8400,3450)","0","mstr_symbols","I8";
;
HDL_POWER"P3V3_STBY"
CDS_LIB"mstr_symbols"
VOLTAGE"3.3"
ROOM"PVCCINFAON_CPU0_CTRL";
"A"15;
%"TAP"
"1","(-5625,4000)","0","mstr_standard","I80";
;
CDS_LIB"mstr_standard"
BODY_TYPE"PLUMBING"
HDL_TAP"TRUE";
"B \NAC \NWC"5;
"S \NAC"
BN"3"137;
%"TAP"
"1","(-5625,4050)","0","mstr_standard","I81";
;
CDS_LIB"mstr_standard"
BODY_TYPE"PLUMBING"
HDL_TAP"TRUE";
"B \NAC \NWC"5;
"S \NAC"
BN"4"138;
%"TAP"
"1","(-5625,3950)","0","mstr_standard","I82";
;
CDS_LIB"mstr_standard"
BODY_TYPE"PLUMBING"
HDL_TAP"TRUE";
"B \NAC \NWC"5;
"S \NAC"
BN"2"136;
%"TAP"
"1","(-7325,4700)","2","mstr_standard","I85";
;
CDS_LIB"mstr_standard"
BODY_TYPE"PLUMBING"
HDL_TAP"TRUE";
"B \NAC \NWC"2;
"S \NAC"
BN"0"172;
%"TAP"
"1","(-7325,4750)","2","mstr_standard","I86";
;
CDS_LIB"mstr_standard"
BODY_TYPE"PLUMBING"
HDL_TAP"TRUE";
"B \NAC \NWC"2;
"S \NAC"
BN"1"170;
%"TAP"
"1","(-7325,4800)","2","mstr_standard","I87";
;
CDS_LIB"mstr_standard"
BODY_TYPE"PLUMBING"
HDL_TAP"TRUE";
"B \NAC \NWC"2;
"S \NAC"
BN"2"168;
%"TAP"
"1","(-7325,4850)","2","mstr_standard","I88";
;
CDS_LIB"mstr_standard"
BODY_TYPE"PLUMBING"
HDL_TAP"TRUE";
"B \NAC \NWC"2;
"S \NAC"
BN"3"27;
%"TAP"
"1","(-7325,4900)","2","mstr_standard","I89";
;
CDS_LIB"mstr_standard"
BODY_TYPE"PLUMBING"
HDL_TAP"TRUE";
"B \NAC \NWC"2;
"S \NAC"
BN"4"26;
%"TAP"
"1","(-7325,4950)","2","mstr_standard","I90";
;
CDS_LIB"mstr_standard"
BODY_TYPE"PLUMBING"
HDL_TAP"TRUE";
"B \NAC \NWC"2;
"S \NAC"
BN"5"25;
%"TAP"
"1","(-7325,5000)","2","mstr_standard","I91";
;
CDS_LIB"mstr_standard"
BODY_TYPE"PLUMBING"
HDL_TAP"TRUE";
"B \NAC \NWC"2;
"S \NAC"
BN"6"24;
%"TAP"
"1","(-7325,5150)","2","mstr_standard","I92";
;
CDS_LIB"mstr_standard"
BODY_TYPE"PLUMBING"
HDL_TAP"TRUE";
"B \NAC \NWC"3;
"S \NAC"
BN"1"171;
%"TAP"
"1","(-7325,5100)","2","mstr_standard","I93";
;
CDS_LIB"mstr_standard"
BODY_TYPE"PLUMBING"
HDL_TAP"TRUE";
"B \NAC \NWC"3;
"S \NAC"
BN"0"23;
%"TAP"
"1","(-7325,5200)","2","mstr_standard","I94";
;
CDS_LIB"mstr_standard"
BODY_TYPE"PLUMBING"
HDL_TAP"TRUE";
"B \NAC \NWC"3;
"S \NAC"
BN"2"169;
%"TAP"
"1","(-7325,5250)","2","mstr_standard","I95";
;
CDS_LIB"mstr_standard"
BODY_TYPE"PLUMBING"
HDL_TAP"TRUE";
"B \NAC \NWC"3;
"S \NAC"
BN"3"167;
%"TAP"
"1","(-7325,5300)","2","mstr_standard","I96";
;
CDS_LIB"mstr_standard"
BODY_TYPE"PLUMBING"
HDL_TAP"TRUE";
"B \NAC \NWC"3;
"S \NAC"
BN"4"166;
%"TAP"
"1","(-7325,5350)","2","mstr_standard","I97";
;
CDS_LIB"mstr_standard"
BODY_TYPE"PLUMBING"
HDL_TAP"TRUE";
"B \NAC \NWC"3;
"S \NAC"
BN"5"165;
%"TAP"
"1","(-7325,5400)","2","mstr_standard","I98";
;
CDS_LIB"mstr_standard"
BODY_TYPE"PLUMBING"
HDL_TAP"TRUE";
"B \NAC \NWC"3;
"S \NAC"
BN"6"164;
%"TAP"
"1","(-5625,4150)","0","mstr_standard","I99";
;
CDS_LIB"mstr_standard"
BODY_TYPE"PLUMBING"
HDL_TAP"TRUE";
"B \NAC \NWC"5;
"S \NAC"
BN"6"140;
END.
